FILE_TYPE = MULTI_PHYS_TABLE;

PART 'LED_4P_V14'
CLASS = DISCRETE 

{========================================================================================}
:CLS_PN             = JEDEC_TYPE         |ALT_SYMBOLS          |DESCRIPTION                                                                              ;
{========================================================================================}
 'G170-10189-01'      = 'SMC_DS4_098X039'  |'(SMC_DS4_098X039)'  |'LED,BLUE/RED/GREEN,465/621/525NM,3.3/2/3.3V,20MA,65/110/400MCD,2.5X0.7MM,RA,SMD'    

END_PART

END.

